# S9S_MB_2U (Grand Teton) — schematic netlist excerpt (pin names and nets, part order shuffled) for the footprints in the layout excerpt that follows; sources: Cadence DE-HDL packaged netlist, KiCad conversion of 03242023_DA0F0TMBIJ0_F0T_Motherboard_J_brd_V01_OCP.brd

U38  9QXL2001BNHGI8  IC  pkg GQFN80_TH_0-5_6X6  page 206
  DIF17  = CLK_100M_OCP_V3_2_D_R_DP
  \dif16#\  = CLK_100M_OCP_V3_2_C_R_DN
  DIF16  = CLK_100M_OCP_V3_2_C_R_DP
  \dif15#\  = CLK_100M_OCP_V3_2_B_R_DN
  DIF15  = CLK_100M_OCP_V3_2_B_R_DP
  \dif14#\  = CLK_100M_OCP_V3_2_A_R_DN
  DIF14  = CLK_100M_OCP_V3_2_A_R_DP
  \dif13#\  = TP_CLK_100M_DIF13_DN
  DIF13  = TP_CLK_100M_DIF13_DP
  \dif12#\  = CLK_100M_OCP_SFF_3_R_DN
  DIF12  = CLK_100M_OCP_SFF_3_R_DP
  \dif11#\  = CLK_100M_OCP_SFF_2_R_DN
  \dif17#\  = CLK_100M_OCP_V3_2_D_R_DN
  \vddo3.3_b2\  = P3V3_DB2000_VDD
  NC1  = NC_CLK_100M_DB2000_NC1
  \^vsadr0_tri\  = PD_DB2000_SMB_SA0
  NC2  = NC_CLK_100M_DB2000_NC2
  \vdda3.3\  = P3V3_DB2000_VDDA
  NC3  = NC_CLK_100M_DB2000_NC3
  \^vsadr1_tri\  = PD_DB2000_SMB_SA1
  NC4  = NC_CLK_100M_DB2000_NC4
  \voe12#\  = FM_DB2000_12_OE_N
  \vddo3.3_b11\  = P3V3_DB2000_VDD
  DIF11  = CLK_100M_OCP_SFF_2_R_DP
  DIF18  = TP_CLK_100M_DIF18_DP
  NC5  = NC_CLK_100M_DB2000_NC5
  \voe11#\  = FM_DB2000_11_OE_N
  \dif10#\  = CLK_100M_OCP_SFF_1_R_DN
  \dif18#\  = TP_CLK_100M_DIF18_DN
  NC6  = NC_CLK_100M_DB2000_NC6
  NC7  = NC_CLK_100M_DB2000_NC7
  DIF10  = CLK_100M_OCP_SFF_1_R_DP
  DIF19  = TP_CLK_100M_DIF19_DP
  VSBEN  = FM_DB2000_VSBEN
  \voe10#||shft_ld#\  = FM_DB2000_10_OE_N
  \voe9#\  = FM_DB2000_9_OE_N
  \dif19#\  = TP_CLK_100M_DIF19_DN
  NC8  = NC_CLK_100M_DB2000_NC8
  NC9  = NC_CLK_100M_DB2000_NC9
  \dif9#\  = CLK_100M_OCP_SFF_0_R_DN
  DIF_IN  = CLK_100M_DB2000_DP
  NC10  = NC_CLK_100M_DB2000_NC10
  NC11  = NC_CLK_100M_DB2000_NC11
  DIF9  = CLK_100M_OCP_SFF_0_R_DP
  \dif_in#\  = CLK_100M_DB2000_DN
  \vddr3.3\  = P3V3_DB2000_VDDR
  \voe8#\  = FM_DB2000_8_OE_N
  \dif8#\  = CLK_100M_GPU_SWB_REF_DN
  DIF0  = CLK_100M_DB2000_CPU0_BCLK0_DP
  NC12  = NC_CLK_100M_DB2000_NC12
  NC13  = NC_CLK_100M_DB2000_NC13
  DIF8  = CLK_100M_GPU_SWB_REF_DP
  \dif0#\  = CLK_100M_DB2000_CPU0_BCLK0_DN
  NC14  = NC_CLK_100M_DB2000_NC14
  \voe7#\  = FM_DB2000_1_OE_N
  \dif7#\  = CLK_100M_DB2000_CPU1_BCLK3_DN
  DIF1  = CLK_100M_DB2000_CPU0_BCLK1_DP
  \vddo3.3_l2\  = P3V3_DB2000_VDD
  NC17  = NC_CLK_100M_DB2000_NC17
  SMBDAT  = SMB_HOST_DB2000_3V3AUX_SDA
  SMBCLK  = SMB_HOST_DB2000_3V3AUX_SCL
  NC15  = NC_CLK_100M_DB2000_NC15
  NC16  = NC_CLK_100M_DB2000_NC16
  \voe5#||data\  = FM_DB2000_1_OE_N
  NC18  = NC_CLK_100M_DB2000_NC18
  \voe6#||clk\  = FM_DB2000_1_OE_N
  \vddo3.3_l11\  = P3V3_DB2000_VDD
  DIF7  = CLK_100M_DB2000_CPU1_BCLK3_DP
  \dif1#\  = CLK_100M_DB2000_CPU0_BCLK1_DN
  DIF2  = CLK_100M_DB2000_CPU0_BCLK2_DP
  \dif2#\  = CLK_100M_DB2000_CPU0_BCLK2_DN
  DIF3  = CLK_100M_DB2000_CPU0_BCLK3_DP
  \dif3#\  = CLK_100M_DB2000_CPU0_BCLK3_DN
  \vckpwrgd_pd#\  = FM_DB2000_DEV_EN
  DIF4  = CLK_100M_DB2000_CPU1_BCLK0_DP
  \dif4#\  = CLK_100M_DB2000_CPU1_BCLK0_DN
  DIF5  = CLK_100M_DB2000_CPU1_BCLK1_DP
  \dif5#\  = CLK_100M_DB2000_CPU1_BCLK1_DN
  DIF6  = CLK_100M_DB2000_CPU1_BCLK2_DP
  \dif6#\  = CLK_100M_DB2000_CPU1_BCLK2_DN
  EPAD  = GND

(kicad_pcb
	(version 20260206)
	(generator "pcbnew")
	(generator_version "10.0")
	(general
		(thickness 1.6)
		(legacy_teardrops no)
	)
	(paper "A4")
	(title_block
		(title "03242023_DA0F0TMBIJ0_F0T_Motherboard_J_brd_V01_OCP.brd")
		(comment 1 "Grand Teton / footprint 4091 of 6105 (U38), pads 1-42 of 81")
	)
	(layers
		(0 "F.Cu" signal "TOP")
		(4 "In1.Cu" signal "GND")
		(6 "In2.Cu" signal "IN1")
		(8 "In3.Cu" signal "GND1")
		(10 "In4.Cu" signal "IN2")
		(12 "In5.Cu" signal "GND2")
		(14 "In6.Cu" signal "IN3")
		(16 "In7.Cu" signal "GND3")
		(18 "In8.Cu" signal "VCC")
		(20 "In9.Cu" signal "VCC1")
		(22 "In10.Cu" signal "GND4")
		(24 "In11.Cu" signal "IN4")
		(26 "In12.Cu" signal "GND5")
		(28 "In13.Cu" signal "IN5")
		(30 "In14.Cu" signal "GND6")
		(32 "In15.Cu" signal "IN6")
		(34 "In16.Cu" signal "GND7")
		(2 "B.Cu" signal "BOTTOM")
		(9 "F.Adhes" user "F.Adhesive")
		(11 "B.Adhes" user "B.Adhesive")
		(13 "F.Paste" user "Package Geometry/Pastemask Top")
		(15 "B.Paste" user "Package Geometry/Pastemask Bottom")
		(5 "F.SilkS" user "Ref Des/Silkscreen Top")
		(7 "B.SilkS" user "Ref Des/Silkscreen Bottom")
		(1 "F.Mask" user "Board Geometry/Soldermask Top")
		(3 "B.Mask" user "Board Geometry/Soldermask Bottom")
		(17 "Dwgs.User" user "User.Drawings")
		(19 "Cmts.User" user "User.Comments")
		(21 "Eco1.User" user "User.Eco1")
		(23 "Eco2.User" user "User.Eco2")
		(25 "Edge.Cuts" user "Board Geometry/Outline")
		(27 "Margin" user)
		(31 "F.CrtYd" user "Package Geometry/Place Bound Top")
		(29 "B.CrtYd" user "Package Geometry/Place Bound Bottom")
		(35 "F.Fab" user "Ref Des/Assembly Top")
		(33 "B.Fab" user "Ref Des/Assembly Bottom")
	)
	(footprint ""
		(layer "F.Cu")
		(at 234.998006 -126.767844 180)
		(property "Reference" "U38"
			(at -6.147308 -6.293104 0)
			(unlocked yes)
			(layer "F.SilkS")
			(effects
				(font
					(size 0.7874 0.5842)
					(thickness 0.1524)
				)
				(justify left)
			)
		)
		(property "Value" ""
			(at 0 0 180)
			(layer "F.Fab")
			(effects
				(font
					(size 1.27 1.27)
				)
			)
		)
		(duplicate_pad_numbers_are_jumpers no)
		(pad "A1" smd circle
			(at -2.750058 -2.750058 180)
			(size 0.2286 0.2286)
			(layers "F.Cu" "F.Mask" "F.Paste")
			(net "CLK_100M_OCP_V3_2_D_R_DP")
		)
		(pad "A2" smd circle
			(at -2.249932 -2.750058 180)
			(size 0.2286 0.2286)
			(layers "F.Cu" "F.Mask" "F.Paste")
			(net "CLK_100M_OCP_V3_2_C_R_DN")
		)
		(pad "A3" smd circle
			(at -1.75006 -2.750058 180)
			(size 0.2286 0.2286)
			(layers "F.Cu" "F.Mask" "F.Paste")
			(net "CLK_100M_OCP_V3_2_C_R_DP")
		)
		(pad "A4" smd circle
			(at -1.249934 -2.750058 180)
			(size 0.2286 0.2286)
			(layers "F.Cu" "F.Mask" "F.Paste")
			(net "CLK_100M_OCP_V3_2_B_R_DN")
		)
		(pad "A5" smd circle
			(at -0.750062 -2.750058 180)
			(size 0.2286 0.2286)
			(layers "F.Cu" "F.Mask" "F.Paste")
			(net "CLK_100M_OCP_V3_2_B_R_DP")
		)
		(pad "A6" smd circle
			(at -0.249936 -2.750058 180)
			(size 0.2286 0.2286)
			(layers "F.Cu" "F.Mask" "F.Paste")
			(net "CLK_100M_OCP_V3_2_A_R_DN")
		)
		(pad "A7" smd circle
			(at 0.249936 -2.750058 180)
			(size 0.2286 0.2286)
			(layers "F.Cu" "F.Mask" "F.Paste")
			(net "CLK_100M_OCP_V3_2_A_R_DP")
		)
		(pad "A8" smd circle
			(at 0.750062 -2.750058 180)
			(size 0.2286 0.2286)
			(layers "F.Cu" "F.Mask" "F.Paste")
			(net "TP_CLK_100M_DIF13_DN")
		)
		(pad "A9" smd circle
			(at 1.249934 -2.750058 180)
			(size 0.2286 0.2286)
			(layers "F.Cu" "F.Mask" "F.Paste")
			(net "TP_CLK_100M_DIF13_DP")
		)
		(pad "A10" smd circle
			(at 1.75006 -2.750058 180)
			(size 0.2286 0.2286)
			(layers "F.Cu" "F.Mask" "F.Paste")
			(net "CLK_100M_OCP_SFF_3_R_DN")
		)
		(pad "A11" smd circle
			(at 2.249932 -2.750058 180)
			(size 0.2286 0.2286)
			(layers "F.Cu" "F.Mask" "F.Paste")
			(net "CLK_100M_OCP_SFF_3_R_DP")
		)
		(pad "A12" smd circle
			(at 2.750058 -2.750058 180)
			(size 0.2286 0.2286)
			(layers "F.Cu" "F.Mask" "F.Paste")
			(net "CLK_100M_OCP_SFF_2_R_DN")
		)
		(pad "B1" smd circle
			(at -2.750058 -2.249932 180)
			(size 0.2286 0.2286)
			(layers "F.Cu" "F.Mask" "F.Paste")
			(net "CLK_100M_OCP_V3_2_D_R_DN")
		)
		(pad "B2" smd circle
			(at -2.249932 -2.249932 180)
			(size 0.2286 0.2286)
			(layers "F.Cu" "F.Mask" "F.Paste")
			(net "P3V3_DB2000_VDD")
		)
		(pad "B3" smd circle
			(at -1.75006 -2.249932 180)
			(size 0.2286 0.2286)
			(layers "F.Cu" "F.Mask" "F.Paste")
			(net "NC_CLK_100M_DB2000_NC1")
		)
		(pad "B4" smd circle
			(at -1.249934 -2.249932 180)
			(size 0.2286 0.2286)
			(layers "F.Cu" "F.Mask" "F.Paste")
			(net "PD_DB2000_SMB_SA0")
		)
		(pad "B5" smd circle
			(at -0.750062 -2.249932 180)
			(size 0.2286 0.2286)
			(layers "F.Cu" "F.Mask" "F.Paste")
			(net "NC_CLK_100M_DB2000_NC2")
		)
		(pad "B6" smd circle
			(at -0.249936 -2.249932 180)
			(size 0.2286 0.2286)
			(layers "F.Cu" "F.Mask" "F.Paste")
			(net "P3V3_DB2000_VDDA")
		)
		(pad "B7" smd circle
			(at 0.249936 -2.249932 180)
			(size 0.2286 0.2286)
			(layers "F.Cu" "F.Mask" "F.Paste")
			(net "NC_CLK_100M_DB2000_NC3")
		)
		(pad "B8" smd circle
			(at 0.750062 -2.249932 180)
			(size 0.2286 0.2286)
			(layers "F.Cu" "F.Mask" "F.Paste")
			(net "PD_DB2000_SMB_SA1")
		)
		(pad "B9" smd circle
			(at 1.249934 -2.249932 180)
			(size 0.2286 0.2286)
			(layers "F.Cu" "F.Mask" "F.Paste")
			(net "NC_CLK_100M_DB2000_NC4")
		)
		(pad "B10" smd circle
			(at 1.75006 -2.249932 180)
			(size 0.2286 0.2286)
			(layers "F.Cu" "F.Mask" "F.Paste")
			(net "FM_DB2000_12_OE_N")
		)
		(pad "B11" smd circle
			(at 2.249932 -2.249932 180)
			(size 0.2286 0.2286)
			(layers "F.Cu" "F.Mask" "F.Paste")
			(net "P3V3_DB2000_VDD")
		)
		(pad "B12" smd circle
			(at 2.750058 -2.249932 180)
			(size 0.2286 0.2286)
			(layers "F.Cu" "F.Mask" "F.Paste")
			(net "CLK_100M_OCP_SFF_2_R_DP")
		)
		(pad "C1" smd circle
			(at -2.750058 -1.75006 180)
			(size 0.2286 0.2286)
			(layers "F.Cu" "F.Mask" "F.Paste")
			(net "TP_CLK_100M_DIF18_DP")
		)
		(pad "C2" smd circle
			(at -2.249932 -1.75006 180)
			(size 0.2286 0.2286)
			(layers "F.Cu" "F.Mask" "F.Paste")
			(net "NC_CLK_100M_DB2000_NC5")
		)
		(pad "C11" smd circle
			(at 2.249932 -1.75006 180)
			(size 0.2286 0.2286)
			(layers "F.Cu" "F.Mask" "F.Paste")
			(net "FM_DB2000_11_OE_N")
		)
		(pad "C12" smd circle
			(at 2.750058 -1.75006 180)
			(size 0.2286 0.2286)
			(layers "F.Cu" "F.Mask" "F.Paste")
			(net "CLK_100M_OCP_SFF_1_R_DN")
		)
		(pad "D1" smd circle
			(at -2.750058 -1.249934 180)
			(size 0.2286 0.2286)
			(layers "F.Cu" "F.Mask" "F.Paste")
			(net "TP_CLK_100M_DIF18_DN")
		)
		(pad "D2" smd circle
			(at -2.249932 -1.249934 180)
			(size 0.2286 0.2286)
			(layers "F.Cu" "F.Mask" "F.Paste")
			(net "NC_CLK_100M_DB2000_NC6")
		)
		(pad "D11" smd circle
			(at 2.249932 -1.249934 180)
			(size 0.2286 0.2286)
			(layers "F.Cu" "F.Mask" "F.Paste")
			(net "NC_CLK_100M_DB2000_NC7")
		)
		(pad "D12" smd circle
			(at 2.750058 -1.249934 180)
			(size 0.2286 0.2286)
			(layers "F.Cu" "F.Mask" "F.Paste")
			(net "CLK_100M_OCP_SFF_1_R_DP")
		)
		(pad "E1" smd circle
			(at -2.750058 -0.750062 180)
			(size 0.2286 0.2286)
			(layers "F.Cu" "F.Mask" "F.Paste")
			(net "TP_CLK_100M_DIF19_DP")
		)
		(pad "E2" smd circle
			(at -2.249932 -0.750062 180)
			(size 0.2286 0.2286)
			(layers "F.Cu" "F.Mask" "F.Paste")
			(net "FM_DB2000_VSBEN")
		)
		(pad "E11" smd circle
			(at 2.249932 -0.750062 180)
			(size 0.2286 0.2286)
			(layers "F.Cu" "F.Mask" "F.Paste")
			(net "FM_DB2000_10_OE_N")
		)
		(pad "E12" smd circle
			(at 2.750058 -0.750062 180)
			(size 0.2286 0.2286)
			(layers "F.Cu" "F.Mask" "F.Paste")
			(net "FM_DB2000_9_OE_N")
		)
		(pad "F1" smd circle
			(at -2.750058 -0.249936 180)
			(size 0.2286 0.2286)
			(layers "F.Cu" "F.Mask" "F.Paste")
			(net "TP_CLK_100M_DIF19_DN")
		)
		(pad "F2" smd circle
			(at -2.249932 -0.249936 180)
			(size 0.2286 0.2286)
			(layers "F.Cu" "F.Mask" "F.Paste")
			(net "NC_CLK_100M_DB2000_NC8")
		)
		(pad "F11" smd circle
			(at 2.249932 -0.249936 180)
			(size 0.2286 0.2286)
			(layers "F.Cu" "F.Mask" "F.Paste")
			(net "NC_CLK_100M_DB2000_NC9")
		)
		(pad "F12" smd circle
			(at 2.750058 -0.249936 180)
			(size 0.2286 0.2286)
			(layers "F.Cu" "F.Mask" "F.Paste")
			(net "CLK_100M_OCP_SFF_0_R_DN")
		)
		(pad "G1" smd circle
			(at -2.750058 0.249936 180)
			(size 0.2286 0.2286)
			(layers "F.Cu" "F.Mask" "F.Paste")
			(net "CLK_100M_DB2000_DP")
		)
		(pad "G2" smd circle
			(at -2.249932 0.249936 180)
			(size 0.2286 0.2286)
			(layers "F.Cu" "F.Mask" "F.Paste")
			(net "NC_CLK_100M_DB2000_NC10")
		)
	)
)
